(kicad_pcb
	(version 20260206)
	(generator "pcbnew")
	(generator_version "10.0")
	(general
		(thickness 1.6)
		(legacy_teardrops no)
	)
	(paper "A4")
	(title_block
		(title "9052_F0T_PDB_Converter_Brick_F_V03_1208_1600_OCP.brd")
		(comment 1 "Grand Teton / footprints 504-509 of 578")
	)
	(layers
		(0 "F.Cu" signal "TOP")
		(4 "In1.Cu" signal "GND")
		(6 "In2.Cu" signal "IN1")
		(8 "In3.Cu" signal "GND1")
		(10 "In4.Cu" signal "VCC")
		(12 "In5.Cu" signal "VCC1")
		(14 "In6.Cu" signal "GND2")
		(16 "In7.Cu" signal "IN2")
		(18 "In8.Cu" signal "GND3")
		(2 "B.Cu" signal "BOTTOM")
		(9 "F.Adhes" user "F.Adhesive")
		(11 "B.Adhes" user "B.Adhesive")
		(13 "F.Paste" user "Package Geometry/Pastemask Top")
		(15 "B.Paste" user "Package Geometry/Pastemask Bottom")
		(5 "F.SilkS" user "Ref Des/Silkscreen Top")
		(7 "B.SilkS" user "Ref Des/Silkscreen Bottom")
		(1 "F.Mask" user "Board Geometry/Soldermask Top")
		(3 "B.Mask" user "Board Geometry/Soldermask Bottom")
		(17 "Dwgs.User" user "User.Drawings")
		(19 "Cmts.User" user "User.Comments")
		(21 "Eco1.User" user "User.Eco1")
		(23 "Eco2.User" user "User.Eco2")
		(25 "Edge.Cuts" user "Board Geometry/Outline")
		(27 "Margin" user)
		(31 "F.CrtYd" user "Package Geometry/Place Bound Top")
		(29 "B.CrtYd" user "Package Geometry/Place Bound Bottom")
		(35 "F.Fab" user "Ref Des/Assembly Top")
		(33 "B.Fab" user "Ref Des/Assembly Bottom")
	)
	(footprint ""
		(layer "B.Cu")
		(at 220.98 -78.359 -90)
		(property "Reference" "R38"
			(at 0 0 90)
			(layer "B.SilkS")
			(hide yes)
			(effects
				(font
					(size 1.27 1.27)
				)
				(justify mirror)
			)
		)
		(property "Value" ""
			(at 0 0 90)
			(layer "B.Fab")
			(effects
				(font
					(size 1.27 1.27)
				)
				(justify mirror)
			)
		)
		(duplicate_pad_numbers_are_jumpers no)
		(fp_line
			(start -0.7874 0.4064)
			(end 0.7874 0.4064)
			(stroke
				(width 0.1524)
				(type default)
			)
			(layer "B.SilkS")
		)
		(fp_line
			(start 0.7874 0.4064)
			(end 0.7874 -0.4064)
			(stroke
				(width 0.1524)
				(type default)
			)
			(layer "B.SilkS")
		)
		(fp_line
			(start -0.7874 -0.4064)
			(end -0.7874 0.4064)
			(stroke
				(width 0.1524)
				(type default)
			)
			(layer "B.SilkS")
		)
		(fp_line
			(start 0.7874 -0.4064)
			(end -0.7874 -0.4064)
			(stroke
				(width 0.1524)
				(type default)
			)
			(layer "B.SilkS")
		)
		(fp_line
			(start -0.67945 0.3048)
			(end -0.120396 0.3048)
			(stroke
				(width 0.1)
				(type default)
			)
			(layer "B.Fab")
		)
		(fp_line
			(start -0.120396 0.3048)
			(end -0.120396 0.2794)
			(stroke
				(width 0.1)
				(type default)
			)
			(layer "B.Fab")
		)
		(fp_line
			(start 0.12065 0.3048)
			(end 0.67945 0.3048)
			(stroke
				(width 0.1)
				(type default)
			)
			(layer "B.Fab")
		)
		(fp_line
			(start 0.67945 0.3048)
			(end 0.67945 -0.305054)
			(stroke
				(width 0.1)
				(type default)
			)
			(layer "B.Fab")
		)
		(fp_line
			(start -0.120396 0.2794)
			(end 0.12065 0.2794)
			(stroke
				(width 0.1)
				(type default)
			)
			(layer "B.Fab")
		)
		(fp_line
			(start 0.12065 0.2794)
			(end 0.12065 0.3048)
			(stroke
				(width 0.1)
				(type default)
			)
			(layer "B.Fab")
		)
		(fp_line
			(start -0.12065 -0.2794)
			(end -0.12065 -0.3048)
			(stroke
				(width 0.1)
				(type default)
			)
			(layer "B.Fab")
		)
		(fp_line
			(start 0.12065 -0.2794)
			(end -0.12065 -0.2794)
			(stroke
				(width 0.1)
				(type default)
			)
			(layer "B.Fab")
		)
		(fp_line
			(start -0.67945 -0.3048)
			(end -0.67945 0.3048)
			(stroke
				(width 0.1)
				(type default)
			)
			(layer "B.Fab")
		)
		(fp_line
			(start -0.12065 -0.3048)
			(end -0.67945 -0.3048)
			(stroke
				(width 0.1)
				(type default)
			)
			(layer "B.Fab")
		)
		(fp_line
			(start 0.12065 -0.305054)
			(end 0.12065 -0.2794)
			(stroke
				(width 0.1)
				(type default)
			)
			(layer "B.Fab")
		)
		(fp_line
			(start 0.67945 -0.305054)
			(end 0.12065 -0.305054)
			(stroke
				(width 0.1)
				(type default)
			)
			(layer "B.Fab")
		)
		(pad "1" smd circle
			(at 0.40005 0 90)
			(size 0 0)
			(layers "B.Cu" "B.Mask" "B.Paste")
			(net "P3V3_AUX")
		)
		(pad "2" smd circle
			(at -0.40005 0 90)
			(size 0 0)
			(layers "B.Cu" "B.Mask" "B.Paste")
			(net "FRU_ADDR2")
		)
	)
	(footprint ""
		(layer "B.Cu")
		(at 202.946 -90.678)
		(property "Reference" "R102"
			(at 0 0 0)
			(layer "B.SilkS")
			(hide yes)
			(effects
				(font
					(size 1.27 1.27)
				)
				(justify mirror)
			)
		)
		(property "Value" ""
			(at 0 0 0)
			(layer "B.Fab")
			(effects
				(font
					(size 1.27 1.27)
				)
				(justify mirror)
			)
		)
		(duplicate_pad_numbers_are_jumpers no)
		(fp_line
			(start -0.7874 -0.4064)
			(end -0.7874 0.4064)
			(stroke
				(width 0.1524)
				(type default)
			)
			(layer "B.SilkS")
		)
		(fp_line
			(start -0.7874 0.4064)
			(end 0.7874 0.4064)
			(stroke
				(width 0.1524)
				(type default)
			)
			(layer "B.SilkS")
		)
		(fp_line
			(start 0.7874 -0.4064)
			(end -0.7874 -0.4064)
			(stroke
				(width 0.1524)
				(type default)
			)
			(layer "B.SilkS")
		)
		(fp_line
			(start 0.7874 0.4064)
			(end 0.7874 -0.4064)
			(stroke
				(width 0.1524)
				(type default)
			)
			(layer "B.SilkS")
		)
		(fp_line
			(start -0.67945 -0.3048)
			(end -0.67945 0.3048)
			(stroke
				(width 0.1)
				(type default)
			)
			(layer "B.Fab")
		)
		(fp_line
			(start -0.67945 0.3048)
			(end -0.120396 0.3048)
			(stroke
				(width 0.1)
				(type default)
			)
			(layer "B.Fab")
		)
		(fp_line
			(start -0.12065 -0.3048)
			(end -0.67945 -0.3048)
			(stroke
				(width 0.1)
				(type default)
			)
			(layer "B.Fab")
		)
		(fp_line
			(start -0.12065 -0.2794)
			(end -0.12065 -0.3048)
			(stroke
				(width 0.1)
				(type default)
			)
			(layer "B.Fab")
		)
		(fp_line
			(start -0.120396 0.2794)
			(end 0.12065 0.2794)
			(stroke
				(width 0.1)
				(type default)
			)
			(layer "B.Fab")
		)
		(fp_line
			(start -0.120396 0.3048)
			(end -0.120396 0.2794)
			(stroke
				(width 0.1)
				(type default)
			)
			(layer "B.Fab")
		)
		(fp_line
			(start 0.12065 -0.305054)
			(end 0.12065 -0.2794)
			(stroke
				(width 0.1)
				(type default)
			)
			(layer "B.Fab")
		)
		(fp_line
			(start 0.12065 -0.2794)
			(end -0.12065 -0.2794)
			(stroke
				(width 0.1)
				(type default)
			)
			(layer "B.Fab")
		)
		(fp_line
			(start 0.12065 0.2794)
			(end 0.12065 0.3048)
			(stroke
				(width 0.1)
				(type default)
			)
			(layer "B.Fab")
		)
		(fp_line
			(start 0.12065 0.3048)
			(end 0.67945 0.3048)
			(stroke
				(width 0.1)
				(type default)
			)
			(layer "B.Fab")
		)
		(fp_line
			(start 0.67945 -0.305054)
			(end 0.12065 -0.305054)
			(stroke
				(width 0.1)
				(type default)
			)
			(layer "B.Fab")
		)
		(fp_line
			(start 0.67945 0.3048)
			(end 0.67945 -0.305054)
			(stroke
				(width 0.1)
				(type default)
			)
			(layer "B.Fab")
		)
		(pad "1" smd circle
			(at 0.40005 0 180)
			(size 0 0)
			(layers "B.Cu" "B.Mask" "B.Paste")
			(net "P3V3_AUX")
		)
		(pad "2" smd circle
			(at -0.40005 0 180)
			(size 0 0)
			(layers "B.Cu" "B.Mask" "B.Paste")
			(net "PCA9543_MISC_A1")
		)
	)
	(footprint ""
		(layer "B.Cu")
		(at 276.733 -41.656)
		(property "Reference" "PC12"
			(at 0 0 0)
			(layer "B.SilkS")
			(hide yes)
			(effects
				(font
					(size 1.27 1.27)
				)
				(justify mirror)
			)
		)
		(property "Value" ""
			(at 0 0 0)
			(layer "B.Fab")
			(effects
				(font
					(size 1.27 1.27)
				)
				(justify mirror)
			)
		)
		(duplicate_pad_numbers_are_jumpers no)
		(fp_line
			(start -0.7874 -0.4064)
			(end -0.7874 0.4064)
			(stroke
				(width 0.1524)
				(type default)
			)
			(layer "B.SilkS")
		)
		(fp_line
			(start -0.7874 0.4064)
			(end 0.7874 0.4064)
			(stroke
				(width 0.1524)
				(type default)
			)
			(layer "B.SilkS")
		)
		(fp_line
			(start 0.7874 -0.4064)
			(end -0.7874 -0.4064)
			(stroke
				(width 0.1524)
				(type default)
			)
			(layer "B.SilkS")
		)
		(fp_line
			(start 0.7874 0.4064)
			(end 0.7874 -0.4064)
			(stroke
				(width 0.1524)
				(type default)
			)
			(layer "B.SilkS")
		)
		(fp_line
			(start -0.67945 -0.3048)
			(end -0.67945 0.3048)
			(stroke
				(width 0.1)
				(type default)
			)
			(layer "B.Fab")
		)
		(fp_line
			(start -0.67945 0.3048)
			(end -0.120396 0.3048)
			(stroke
				(width 0.1)
				(type default)
			)
			(layer "B.Fab")
		)
		(fp_line
			(start -0.12065 -0.3048)
			(end -0.67945 -0.3048)
			(stroke
				(width 0.1)
				(type default)
			)
			(layer "B.Fab")
		)
		(fp_line
			(start -0.12065 -0.2794)
			(end -0.12065 -0.3048)
			(stroke
				(width 0.1)
				(type default)
			)
			(layer "B.Fab")
		)
		(fp_line
			(start -0.120396 0.2794)
			(end 0.12065 0.2794)
			(stroke
				(width 0.1)
				(type default)
			)
			(layer "B.Fab")
		)
		(fp_line
			(start -0.120396 0.3048)
			(end -0.120396 0.2794)
			(stroke
				(width 0.1)
				(type default)
			)
			(layer "B.Fab")
		)
		(fp_line
			(start 0.12065 -0.305054)
			(end 0.12065 -0.2794)
			(stroke
				(width 0.1)
				(type default)
			)
			(layer "B.Fab")
		)
		(fp_line
			(start 0.12065 -0.2794)
			(end -0.12065 -0.2794)
			(stroke
				(width 0.1)
				(type default)
			)
			(layer "B.Fab")
		)
		(fp_line
			(start 0.12065 0.2794)
			(end 0.12065 0.3048)
			(stroke
				(width 0.1)
				(type default)
			)
			(layer "B.Fab")
		)
		(fp_line
			(start 0.12065 0.3048)
			(end 0.67945 0.3048)
			(stroke
				(width 0.1)
				(type default)
			)
			(layer "B.Fab")
		)
		(fp_line
			(start 0.67945 -0.305054)
			(end 0.12065 -0.305054)
			(stroke
				(width 0.1)
				(type default)
			)
			(layer "B.Fab")
		)
		(fp_line
			(start 0.67945 0.3048)
			(end 0.67945 -0.305054)
			(stroke
				(width 0.1)
				(type default)
			)
			(layer "B.Fab")
		)
		(pad "1" smd circle
			(at 0.40005 0 180)
			(size 0 0)
			(layers "B.Cu" "B.Mask" "B.Paste")
			(net "P52V_HS1_EFAULT")
		)
		(pad "2" smd circle
			(at -0.40005 0 180)
			(size 0 0)
			(layers "B.Cu" "B.Mask" "B.Paste")
			(net "GND_FIELD_SIGNAL")
		)
	)
	(footprint ""
		(layer "B.Cu")
		(at 208.661 -90.551 -90)
		(property "Reference" "R30"
			(at 0 0 90)
			(layer "B.SilkS")
			(hide yes)
			(effects
				(font
					(size 1.27 1.27)
				)
				(justify mirror)
			)
		)
		(property "Value" ""
			(at 0 0 90)
			(layer "B.Fab")
			(effects
				(font
					(size 1.27 1.27)
				)
				(justify mirror)
			)
		)
		(duplicate_pad_numbers_are_jumpers no)
		(fp_line
			(start -0.7874 0.4064)
			(end 0.7874 0.4064)
			(stroke
				(width 0.1524)
				(type default)
			)
			(layer "B.SilkS")
		)
		(fp_line
			(start 0.7874 0.4064)
			(end 0.7874 -0.4064)
			(stroke
				(width 0.1524)
				(type default)
			)
			(layer "B.SilkS")
		)
		(fp_line
			(start -0.7874 -0.4064)
			(end -0.7874 0.4064)
			(stroke
				(width 0.1524)
				(type default)
			)
			(layer "B.SilkS")
		)
		(fp_line
			(start 0.7874 -0.4064)
			(end -0.7874 -0.4064)
			(stroke
				(width 0.1524)
				(type default)
			)
			(layer "B.SilkS")
		)
		(fp_line
			(start -0.67945 0.3048)
			(end -0.120396 0.3048)
			(stroke
				(width 0.1)
				(type default)
			)
			(layer "B.Fab")
		)
		(fp_line
			(start -0.120396 0.3048)
			(end -0.120396 0.2794)
			(stroke
				(width 0.1)
				(type default)
			)
			(layer "B.Fab")
		)
		(fp_line
			(start 0.12065 0.3048)
			(end 0.67945 0.3048)
			(stroke
				(width 0.1)
				(type default)
			)
			(layer "B.Fab")
		)
		(fp_line
			(start 0.67945 0.3048)
			(end 0.67945 -0.305054)
			(stroke
				(width 0.1)
				(type default)
			)
			(layer "B.Fab")
		)
		(fp_line
			(start -0.120396 0.2794)
			(end 0.12065 0.2794)
			(stroke
				(width 0.1)
				(type default)
			)
			(layer "B.Fab")
		)
		(fp_line
			(start 0.12065 0.2794)
			(end 0.12065 0.3048)
			(stroke
				(width 0.1)
				(type default)
			)
			(layer "B.Fab")
		)
		(fp_line
			(start -0.12065 -0.2794)
			(end -0.12065 -0.3048)
			(stroke
				(width 0.1)
				(type default)
			)
			(layer "B.Fab")
		)
		(fp_line
			(start 0.12065 -0.2794)
			(end -0.12065 -0.2794)
			(stroke
				(width 0.1)
				(type default)
			)
			(layer "B.Fab")
		)
		(fp_line
			(start -0.67945 -0.3048)
			(end -0.67945 0.3048)
			(stroke
				(width 0.1)
				(type default)
			)
			(layer "B.Fab")
		)
		(fp_line
			(start -0.12065 -0.3048)
			(end -0.67945 -0.3048)
			(stroke
				(width 0.1)
				(type default)
			)
			(layer "B.Fab")
		)
		(fp_line
			(start 0.12065 -0.305054)
			(end 0.12065 -0.2794)
			(stroke
				(width 0.1)
				(type default)
			)
			(layer "B.Fab")
		)
		(fp_line
			(start 0.67945 -0.305054)
			(end 0.12065 -0.305054)
			(stroke
				(width 0.1)
				(type default)
			)
			(layer "B.Fab")
		)
		(pad "1" smd circle
			(at 0.40005 0 90)
			(size 0 0)
			(layers "B.Cu" "B.Mask" "B.Paste")
			(net "PWRGD_GPU_HSC_BUF")
		)
		(pad "2" smd circle
			(at -0.40005 0 90)
			(size 0 0)
			(layers "B.Cu" "B.Mask" "B.Paste")
			(net "PWRGD_GPU_HSC_BUF_R")
		)
	)
	(footprint ""
		(layer "B.Cu")
		(at 279.908 -46.609 180)
		(property "Reference" "R157"
			(at 0 0 0)
			(layer "B.SilkS")
			(hide yes)
			(effects
				(font
					(size 1.27 1.27)
				)
				(justify mirror)
			)
		)
		(property "Value" ""
			(at 0 0 0)
			(layer "B.Fab")
			(effects
				(font
					(size 1.27 1.27)
				)
				(justify mirror)
			)
		)
		(duplicate_pad_numbers_are_jumpers no)
		(fp_line
			(start 0.7874 0.4064)
			(end 0.7874 -0.4064)
			(stroke
				(width 0.1524)
				(type default)
			)
			(layer "B.SilkS")
		)
		(fp_line
			(start 0.7874 -0.4064)
			(end -0.7874 -0.4064)
			(stroke
				(width 0.1524)
				(type default)
			)
			(layer "B.SilkS")
		)
		(fp_line
			(start -0.7874 0.4064)
			(end 0.7874 0.4064)
			(stroke
				(width 0.1524)
				(type default)
			)
			(layer "B.SilkS")
		)
		(fp_line
			(start -0.7874 -0.4064)
			(end -0.7874 0.4064)
			(stroke
				(width 0.1524)
				(type default)
			)
			(layer "B.SilkS")
		)
		(fp_line
			(start 0.67945 0.3048)
			(end 0.67945 -0.305054)
			(stroke
				(width 0.1)
				(type default)
			)
			(layer "B.Fab")
		)
		(fp_line
			(start 0.67945 -0.305054)
			(end 0.12065 -0.305054)
			(stroke
				(width 0.1)
				(type default)
			)
			(layer "B.Fab")
		)
		(fp_line
			(start 0.12065 0.3048)
			(end 0.67945 0.3048)
			(stroke
				(width 0.1)
				(type default)
			)
			(layer "B.Fab")
		)
		(fp_line
			(start 0.12065 0.2794)
			(end 0.12065 0.3048)
			(stroke
				(width 0.1)
				(type default)
			)
			(layer "B.Fab")
		)
		(fp_line
			(start 0.12065 -0.2794)
			(end -0.12065 -0.2794)
			(stroke
				(width 0.1)
				(type default)
			)
			(layer "B.Fab")
		)
		(fp_line
			(start 0.12065 -0.305054)
			(end 0.12065 -0.2794)
			(stroke
				(width 0.1)
				(type default)
			)
			(layer "B.Fab")
		)
		(fp_line
			(start -0.120396 0.3048)
			(end -0.120396 0.2794)
			(stroke
				(width 0.1)
				(type default)
			)
			(layer "B.Fab")
		)
		(fp_line
			(start -0.120396 0.2794)
			(end 0.12065 0.2794)
			(stroke
				(width 0.1)
				(type default)
			)
			(layer "B.Fab")
		)
		(fp_line
			(start -0.12065 -0.2794)
			(end -0.12065 -0.3048)
			(stroke
				(width 0.1)
				(type default)
			)
			(layer "B.Fab")
		)
		(fp_line
			(start -0.12065 -0.3048)
			(end -0.67945 -0.3048)
			(stroke
				(width 0.1)
				(type default)
			)
			(layer "B.Fab")
		)
		(fp_line
			(start -0.67945 0.3048)
			(end -0.120396 0.3048)
			(stroke
				(width 0.1)
				(type default)
			)
			(layer "B.Fab")
		)
		(fp_line
			(start -0.67945 -0.3048)
			(end -0.67945 0.3048)
			(stroke
				(width 0.1)
				(type default)
			)
			(layer "B.Fab")
		)
		(pad "1" smd circle
			(at 0.40005 0)
			(size 0 0)
			(layers "B.Cu" "B.Mask" "B.Paste")
			(net "P52V_HS1_VCAP")
		)
		(pad "2" smd circle
			(at -0.40005 0)
			(size 0 0)
			(layers "B.Cu" "B.Mask" "B.Paste")
			(net "P52V_HS1_ADR1")
		)
	)
	(footprint ""
		(layer "B.Cu")
		(at 210.439 -87.884 -90)
		(property "Reference" "U6"
			(at 0.127 -2.00533 270)
			(unlocked yes)
			(layer "B.SilkS")
			(effects
				(font
					(size 0.7874 0.5842)
					(thickness 0.1524)
				)
				(justify left mirror)
			)
		)
		(property "Value" ""
			(at 0 0 90)
			(layer "B.Fab")
			(effects
				(font
					(size 1.27 1.27)
				)
				(justify mirror)
			)
		)
		(duplicate_pad_numbers_are_jumpers no)
		(fp_line
			(start -1.400048 1.100074)
			(end 1.400048 1.100074)
			(stroke
				(width 0.1524)
				(type default)
			)
			(layer "B.SilkS")
		)
		(fp_line
			(start 1.400048 1.100074)
			(end 1.400048 -1.100074)
			(stroke
				(width 0.1524)
				(type default)
			)
			(layer "B.SilkS")
		)
		(fp_line
			(start -1.400048 -1.100074)
			(end -1.400048 1.100074)
			(stroke
				(width 0.1524)
				(type default)
			)
			(layer "B.SilkS")
		)
		(fp_line
			(start -1.400048 -1.100074)
			(end 1.400048 -1.100074)
			(stroke
				(width 0.1524)
				(type default)
			)
			(layer "B.SilkS")
		)
		(fp_poly
			(pts
				(xy 1.001014 -1.463548) (xy 0.493014 -2.479548) (xy 1.509014 -2.479548)
			)
			(stroke
				(width 0)
				(type default)
			)
			(fill yes)
			(layer "B.SilkS")
		)
		(fp_line
			(start -0.674878 1.100074)
			(end 0.674878 1.100074)
			(stroke
				(width 0.1)
				(type default)
			)
			(layer "B.Fab")
		)
		(fp_line
			(start 0.674878 1.100074)
			(end 0.674878 -1.100074)
			(stroke
				(width 0.1)
				(type default)
			)
			(layer "B.Fab")
		)
		(fp_line
			(start -0.674878 -1.100074)
			(end -0.674878 1.100074)
			(stroke
				(width 0.1)
				(type default)
			)
			(layer "B.Fab")
		)
		(fp_line
			(start 0.674878 -1.100074)
			(end -0.674878 -1.100074)
			(stroke
				(width 0.1)
				(type default)
			)
			(layer "B.Fab")
		)
		(fp_poly
			(pts
				(xy 1.590548 -0.649986) (xy 2.606548 -1.157986) (xy 2.606548 -0.141986)
			)
			(stroke
				(width 0)
				(type default)
			)
			(fill yes)
			(layer "B.Fab")
		)
		(pad "1" smd rect
			(at 0.94996 -0.649986 180)
			(size 0.4318 0.6096)
			(layers "B.Cu" "B.Mask" "B.Paste")
			(net "NC_U6")
		)
		(pad "2" smd rect
			(at 0.94996 0 180)
			(size 0.4318 0.6096)
			(layers "B.Cu" "B.Mask" "B.Paste")
			(net "PWRGD_GPU_HSC_R")
		)
		(pad "3" smd rect
			(at 0.94996 0.649986 180)
			(size 0.4318 0.6096)
			(layers "B.Cu" "B.Mask" "B.Paste")
			(net "GND")
		)
		(pad "4" smd rect
			(at -0.94996 0.649986 180)
			(size 0.4318 0.6096)
			(layers "B.Cu" "B.Mask" "B.Paste")
			(net "PWRGD_GPU_HSC_BUF")
		)
		(pad "5" smd rect
			(at -0.94996 -0.649986 180)
			(size 0.4318 0.6096)
			(layers "B.Cu" "B.Mask" "B.Paste")
			(net "P3V3_AUX")
		)
	)
)
